(kicad_pcb
	(version 20260206)
	(generator "pcbnew")
	(generator_version "10.0")
	(general
		(thickness 1.6)
		(legacy_teardrops no)
	)
	(paper "A4")
	(title_block
		(title "12092022_DA0F0TFB6D0_F0T_FAN_BOARD_MP5048_D_brd_v02_OCP.brd")
		(comment 1 "Grand Teton / footprints 651-657 of 924")
	)
	(layers
		(0 "F.Cu" signal "TOP")
		(4 "In1.Cu" signal "GND")
		(6 "In2.Cu" signal "IN1")
		(8 "In3.Cu" signal "IN2")
		(10 "In4.Cu" signal "GND1")
		(2 "B.Cu" signal "BOTTOM")
		(9 "F.Adhes" user "F.Adhesive")
		(11 "B.Adhes" user "B.Adhesive")
		(13 "F.Paste" user "Package Geometry/Pastemask Top")
		(15 "B.Paste" user "Package Geometry/Pastemask Bottom")
		(5 "F.SilkS" user "Ref Des/Silkscreen Top")
		(7 "B.SilkS" user "Ref Des/Silkscreen Bottom")
		(1 "F.Mask" user "Board Geometry/Soldermask Top")
		(3 "B.Mask" user "Board Geometry/Soldermask Bottom")
		(17 "Dwgs.User" user "User.Drawings")
		(19 "Cmts.User" user "User.Comments")
		(21 "Eco1.User" user "User.Eco1")
		(23 "Eco2.User" user "User.Eco2")
		(25 "Edge.Cuts" user "Board Geometry/Outline")
		(27 "Margin" user)
		(31 "F.CrtYd" user "Package Geometry/Place Bound Top")
		(29 "B.CrtYd" user "Package Geometry/Place Bound Bottom")
		(35 "F.Fab" user "Ref Des/Assembly Top")
		(33 "B.Fab" user "Ref Des/Assembly Bottom")
	)
	(footprint ""
		(layer "F.Cu")
		(at 34.544 -109.855)
		(property "Reference" "U373"
			(at -1.4478 -1.819148 0)
			(unlocked yes)
			(layer "F.SilkS")
			(effects
				(font
					(size 0.7874 0.5842)
					(thickness 0.1524)
				)
				(justify left)
			)
		)
		(property "Value" ""
			(at 0 0 0)
			(layer "F.Fab")
			(effects
				(font
					(size 1.27 1.27)
				)
			)
		)
		(duplicate_pad_numbers_are_jumpers no)
		(fp_line
			(start -1.335278 -1.100074)
			(end -1.335278 1.100074)
			(stroke
				(width 0.1524)
				(type default)
			)
			(layer "F.SilkS")
		)
		(fp_line
			(start -1.335278 1.100074)
			(end 1.335278 1.100074)
			(stroke
				(width 0.1524)
				(type default)
			)
			(layer "F.SilkS")
		)
		(fp_line
			(start 1.335278 -1.100074)
			(end -1.335278 -1.100074)
			(stroke
				(width 0.1524)
				(type default)
			)
			(layer "F.SilkS")
		)
		(fp_line
			(start 1.335278 1.100074)
			(end 1.335278 -1.100074)
			(stroke
				(width 0.1524)
				(type default)
			)
			(layer "F.SilkS")
		)
		(fp_line
			(start -0.674878 -1.100074)
			(end -0.674878 1.100074)
			(stroke
				(width 0.1)
				(type default)
			)
			(layer "F.Fab")
		)
		(fp_line
			(start -0.674878 1.100074)
			(end 0.674878 1.100074)
			(stroke
				(width 0.1)
				(type default)
			)
			(layer "F.Fab")
		)
		(fp_line
			(start 0.674878 -1.100074)
			(end -0.674878 -1.100074)
			(stroke
				(width 0.1)
				(type default)
			)
			(layer "F.Fab")
		)
		(fp_line
			(start 0.674878 1.100074)
			(end 0.674878 -1.100074)
			(stroke
				(width 0.1)
				(type default)
			)
			(layer "F.Fab")
		)
		(pad "D" smd rect
			(at 0.8001 0 270)
			(size 0.6096 0.8128)
			(layers "F.Cu" "F.Mask" "F.Paste")
			(net "FAN_2_FAIL_LED_R_N")
		)
		(pad "G" smd rect
			(at -0.8001 -0.649986 270)
			(size 0.6096 0.8128)
			(layers "F.Cu" "F.Mask" "F.Paste")
			(net "FAN_2_FAIL_R_LED")
		)
		(pad "S" smd rect
			(at -0.8001 0.649986 270)
			(size 0.6096 0.8128)
			(layers "F.Cu" "F.Mask" "F.Paste")
			(net "GND")
		)
	)
	(footprint ""
		(layer "F.Cu")
		(at 15.621 -169.291)
		(property "Reference" "C1940"
			(at 0 0 0)
			(layer "F.SilkS")
			(hide yes)
			(effects
				(font
					(size 1.27 1.27)
				)
			)
		)
		(property "Value" ""
			(at 0 0 0)
			(layer "F.Fab")
			(effects
				(font
					(size 1.27 1.27)
				)
			)
		)
		(duplicate_pad_numbers_are_jumpers no)
		(fp_line
			(start -0.7874 -0.4064)
			(end 0.7874 -0.4064)
			(stroke
				(width 0.1524)
				(type default)
			)
			(layer "F.SilkS")
		)
		(fp_line
			(start -0.7874 0.4064)
			(end -0.7874 -0.4064)
			(stroke
				(width 0.1524)
				(type default)
			)
			(layer "F.SilkS")
		)
		(fp_line
			(start 0.7874 -0.4064)
			(end 0.7874 0.4064)
			(stroke
				(width 0.1524)
				(type default)
			)
			(layer "F.SilkS")
		)
		(fp_line
			(start 0.7874 0.4064)
			(end -0.7874 0.4064)
			(stroke
				(width 0.1524)
				(type default)
			)
			(layer "F.SilkS")
		)
		(fp_line
			(start -0.67945 -0.305054)
			(end -0.12065 -0.305054)
			(stroke
				(width 0.1)
				(type default)
			)
			(layer "F.Fab")
		)
		(fp_line
			(start -0.67945 0.3048)
			(end -0.67945 -0.305054)
			(stroke
				(width 0.1)
				(type default)
			)
			(layer "F.Fab")
		)
		(fp_line
			(start -0.12065 -0.305054)
			(end -0.12065 -0.2794)
			(stroke
				(width 0.1)
				(type default)
			)
			(layer "F.Fab")
		)
		(fp_line
			(start -0.12065 -0.2794)
			(end 0.12065 -0.2794)
			(stroke
				(width 0.1)
				(type default)
			)
			(layer "F.Fab")
		)
		(fp_line
			(start -0.12065 0.2794)
			(end -0.12065 0.3048)
			(stroke
				(width 0.1)
				(type default)
			)
			(layer "F.Fab")
		)
		(fp_line
			(start -0.12065 0.3048)
			(end -0.67945 0.3048)
			(stroke
				(width 0.1)
				(type default)
			)
			(layer "F.Fab")
		)
		(fp_line
			(start 0.120396 0.2794)
			(end -0.12065 0.2794)
			(stroke
				(width 0.1)
				(type default)
			)
			(layer "F.Fab")
		)
		(fp_line
			(start 0.120396 0.3048)
			(end 0.120396 0.2794)
			(stroke
				(width 0.1)
				(type default)
			)
			(layer "F.Fab")
		)
		(fp_line
			(start 0.12065 -0.3048)
			(end 0.67945 -0.3048)
			(stroke
				(width 0.1)
				(type default)
			)
			(layer "F.Fab")
		)
		(fp_line
			(start 0.12065 -0.2794)
			(end 0.12065 -0.3048)
			(stroke
				(width 0.1)
				(type default)
			)
			(layer "F.Fab")
		)
		(fp_line
			(start 0.67945 -0.3048)
			(end 0.67945 0.3048)
			(stroke
				(width 0.1)
				(type default)
			)
			(layer "F.Fab")
		)
		(fp_line
			(start 0.67945 0.3048)
			(end 0.120396 0.3048)
			(stroke
				(width 0.1)
				(type default)
			)
			(layer "F.Fab")
		)
		(pad "1" smd circle
			(at -0.40005 0)
			(size 0 0)
			(layers "F.Cu" "F.Mask" "F.Paste")
			(net "FAN_4_PRESENT_N")
		)
		(pad "2" smd circle
			(at 0.40005 0)
			(size 0 0)
			(layers "F.Cu" "F.Mask" "F.Paste")
			(net "GND")
		)
	)
	(footprint ""
		(layer "F.Cu")
		(at 32.131 -162.941 90)
		(property "Reference" "R5288"
			(at 0 0 90)
			(layer "F.SilkS")
			(hide yes)
			(effects
				(font
					(size 1.27 1.27)
				)
			)
		)
		(property "Value" ""
			(at 0 0 90)
			(layer "F.Fab")
			(effects
				(font
					(size 1.27 1.27)
				)
			)
		)
		(duplicate_pad_numbers_are_jumpers no)
		(fp_line
			(start 0.7874 -0.4064)
			(end 0.7874 0.4064)
			(stroke
				(width 0.1524)
				(type default)
			)
			(layer "F.SilkS")
		)
		(fp_line
			(start -0.7874 -0.4064)
			(end 0.7874 -0.4064)
			(stroke
				(width 0.1524)
				(type default)
			)
			(layer "F.SilkS")
		)
		(fp_line
			(start 0.7874 0.4064)
			(end -0.7874 0.4064)
			(stroke
				(width 0.1524)
				(type default)
			)
			(layer "F.SilkS")
		)
		(fp_line
			(start -0.7874 0.4064)
			(end -0.7874 -0.4064)
			(stroke
				(width 0.1524)
				(type default)
			)
			(layer "F.SilkS")
		)
		(fp_line
			(start -0.12065 -0.305054)
			(end -0.12065 -0.2794)
			(stroke
				(width 0.1)
				(type default)
			)
			(layer "F.Fab")
		)
		(fp_line
			(start -0.67945 -0.305054)
			(end -0.12065 -0.305054)
			(stroke
				(width 0.1)
				(type default)
			)
			(layer "F.Fab")
		)
		(fp_line
			(start 0.67945 -0.3048)
			(end 0.67945 0.3048)
			(stroke
				(width 0.1)
				(type default)
			)
			(layer "F.Fab")
		)
		(fp_line
			(start 0.12065 -0.3048)
			(end 0.67945 -0.3048)
			(stroke
				(width 0.1)
				(type default)
			)
			(layer "F.Fab")
		)
		(fp_line
			(start 0.12065 -0.2794)
			(end 0.12065 -0.3048)
			(stroke
				(width 0.1)
				(type default)
			)
			(layer "F.Fab")
		)
		(fp_line
			(start -0.12065 -0.2794)
			(end 0.12065 -0.2794)
			(stroke
				(width 0.1)
				(type default)
			)
			(layer "F.Fab")
		)
		(fp_line
			(start 0.120396 0.2794)
			(end -0.12065 0.2794)
			(stroke
				(width 0.1)
				(type default)
			)
			(layer "F.Fab")
		)
		(fp_line
			(start -0.12065 0.2794)
			(end -0.12065 0.3048)
			(stroke
				(width 0.1)
				(type default)
			)
			(layer "F.Fab")
		)
		(fp_line
			(start 0.67945 0.3048)
			(end 0.120396 0.3048)
			(stroke
				(width 0.1)
				(type default)
			)
			(layer "F.Fab")
		)
		(fp_line
			(start 0.120396 0.3048)
			(end 0.120396 0.2794)
			(stroke
				(width 0.1)
				(type default)
			)
			(layer "F.Fab")
		)
		(fp_line
			(start -0.12065 0.3048)
			(end -0.67945 0.3048)
			(stroke
				(width 0.1)
				(type default)
			)
			(layer "F.Fab")
		)
		(fp_line
			(start -0.67945 0.3048)
			(end -0.67945 -0.305054)
			(stroke
				(width 0.1)
				(type default)
			)
			(layer "F.Fab")
		)
		(pad "1" smd circle
			(at -0.40005 0 90)
			(size 0 0)
			(layers "F.Cu" "F.Mask" "F.Paste")
			(net "SMB_FAN4_R_SCL")
		)
		(pad "2" smd circle
			(at 0.40005 0 90)
			(size 0 0)
			(layers "F.Cu" "F.Mask" "F.Paste")
			(net "P3V3_AUX")
		)
	)
	(footprint ""
		(layer "F.Cu")
		(at 24.384 -13.8938 -90)
		(property "Reference" "R4968"
			(at 0 0 270)
			(layer "F.SilkS")
			(hide yes)
			(effects
				(font
					(size 1.27 1.27)
				)
			)
		)
		(property "Value" ""
			(at 0 0 270)
			(layer "F.Fab")
			(effects
				(font
					(size 1.27 1.27)
				)
			)
		)
		(duplicate_pad_numbers_are_jumpers no)
		(fp_line
			(start -0.7874 0.4064)
			(end -0.7874 -0.4064)
			(stroke
				(width 0.1524)
				(type default)
			)
			(layer "F.SilkS")
		)
		(fp_line
			(start 0.7874 0.4064)
			(end -0.7874 0.4064)
			(stroke
				(width 0.1524)
				(type default)
			)
			(layer "F.SilkS")
		)
		(fp_line
			(start -0.7874 -0.4064)
			(end 0.7874 -0.4064)
			(stroke
				(width 0.1524)
				(type default)
			)
			(layer "F.SilkS")
		)
		(fp_line
			(start 0.7874 -0.4064)
			(end 0.7874 0.4064)
			(stroke
				(width 0.1524)
				(type default)
			)
			(layer "F.SilkS")
		)
		(fp_line
			(start -0.67945 0.3048)
			(end -0.67945 -0.305054)
			(stroke
				(width 0.1)
				(type default)
			)
			(layer "F.Fab")
		)
		(fp_line
			(start -0.12065 0.3048)
			(end -0.67945 0.3048)
			(stroke
				(width 0.1)
				(type default)
			)
			(layer "F.Fab")
		)
		(fp_line
			(start 0.120396 0.3048)
			(end 0.120396 0.2794)
			(stroke
				(width 0.1)
				(type default)
			)
			(layer "F.Fab")
		)
		(fp_line
			(start 0.67945 0.3048)
			(end 0.120396 0.3048)
			(stroke
				(width 0.1)
				(type default)
			)
			(layer "F.Fab")
		)
		(fp_line
			(start -0.12065 0.2794)
			(end -0.12065 0.3048)
			(stroke
				(width 0.1)
				(type default)
			)
			(layer "F.Fab")
		)
		(fp_line
			(start 0.120396 0.2794)
			(end -0.12065 0.2794)
			(stroke
				(width 0.1)
				(type default)
			)
			(layer "F.Fab")
		)
		(fp_line
			(start -0.12065 -0.2794)
			(end 0.12065 -0.2794)
			(stroke
				(width 0.1)
				(type default)
			)
			(layer "F.Fab")
		)
		(fp_line
			(start 0.12065 -0.2794)
			(end 0.12065 -0.3048)
			(stroke
				(width 0.1)
				(type default)
			)
			(layer "F.Fab")
		)
		(fp_line
			(start 0.12065 -0.3048)
			(end 0.67945 -0.3048)
			(stroke
				(width 0.1)
				(type default)
			)
			(layer "F.Fab")
		)
		(fp_line
			(start 0.67945 -0.3048)
			(end 0.67945 0.3048)
			(stroke
				(width 0.1)
				(type default)
			)
			(layer "F.Fab")
		)
		(fp_line
			(start -0.67945 -0.305054)
			(end -0.12065 -0.305054)
			(stroke
				(width 0.1)
				(type default)
			)
			(layer "F.Fab")
		)
		(fp_line
			(start -0.12065 -0.305054)
			(end -0.12065 -0.2794)
			(stroke
				(width 0.1)
				(type default)
			)
			(layer "F.Fab")
		)
		(pad "1" smd circle
			(at -0.40005 0 270)
			(size 0 0)
			(layers "F.Cu" "F.Mask" "F.Paste")
			(net "SMB_PDBV_FAN_SCL")
		)
		(pad "2" smd circle
			(at 0.40005 0 270)
			(size 0 0)
			(layers "F.Cu" "F.Mask" "F.Paste")
			(net "SMB_PDBV_FAN_R_SCL")
		)
	)
	(footprint ""
		(layer "F.Cu")
		(at 47.752 -125.984)
		(property "Reference" "C2036"
			(at 0 0 0)
			(layer "F.SilkS")
			(hide yes)
			(effects
				(font
					(size 1.27 1.27)
				)
			)
		)
		(property "Value" ""
			(at 0 0 0)
			(layer "F.Fab")
			(effects
				(font
					(size 1.27 1.27)
				)
			)
		)
		(duplicate_pad_numbers_are_jumpers no)
		(fp_line
			(start -1.524 -0.762)
			(end 1.524 -0.762)
			(stroke
				(width 0.1524)
				(type default)
			)
			(layer "F.SilkS")
		)
		(fp_line
			(start -1.524 0.762)
			(end -1.524 -0.762)
			(stroke
				(width 0.1524)
				(type default)
			)
			(layer "F.SilkS")
		)
		(fp_line
			(start 1.524 -0.762)
			(end 1.524 0.762)
			(stroke
				(width 0.1524)
				(type default)
			)
			(layer "F.SilkS")
		)
		(fp_line
			(start 1.524 0.762)
			(end -1.524 0.762)
			(stroke
				(width 0.1524)
				(type default)
			)
			(layer "F.SilkS")
		)
		(fp_line
			(start -1.1049 -0.724916)
			(end -1.1049 0.724916)
			(stroke
				(width 0.1)
				(type default)
			)
			(layer "F.Fab")
		)
		(fp_line
			(start -1.1049 0.724916)
			(end 1.1049 0.724916)
			(stroke
				(width 0.1)
				(type default)
			)
			(layer "F.Fab")
		)
		(fp_line
			(start 1.1049 -0.724916)
			(end -1.1049 -0.724916)
			(stroke
				(width 0.1)
				(type default)
			)
			(layer "F.Fab")
		)
		(fp_line
			(start 1.1049 0.724916)
			(end 1.1049 -0.724916)
			(stroke
				(width 0.1)
				(type default)
			)
			(layer "F.Fab")
		)
		(pad "1" smd rect
			(at -0.889 0 180)
			(size 1.016 1.27)
			(layers "F.Cu" "F.Mask" "F.Paste")
			(net "P12V_LED_FAN2")
		)
		(pad "2" smd rect
			(at 0.889 0 180)
			(size 1.016 1.27)
			(layers "F.Cu" "F.Mask" "F.Paste")
			(net "GND")
		)
	)
	(footprint ""
		(layer "F.Cu")
		(at 37.338 -20.279868)
		(property "Reference" "D282"
			(at 1.27 -0.648462 0)
			(unlocked yes)
			(layer "F.SilkS")
			(effects
				(font
					(size 0.7874 0.5842)
					(thickness 0.1524)
				)
				(justify left)
			)
		)
		(property "Value" ""
			(at 0 0 0)
			(layer "F.Fab")
			(effects
				(font
					(size 1.27 1.27)
				)
			)
		)
		(duplicate_pad_numbers_are_jumpers no)
		(fp_line
			(start -0.854964 -0.450088)
			(end -0.854964 0.450088)
			(stroke
				(width 0.1524)
				(type default)
			)
			(layer "F.SilkS")
		)
		(fp_line
			(start -0.854964 0.450088)
			(end 0.925068 0.450088)
			(stroke
				(width 0.1524)
				(type default)
			)
			(layer "F.SilkS")
		)
		(fp_line
			(start 0.845058 0.4064)
			(end 0.845058 -0.381)
			(stroke
				(width 0.1524)
				(type default)
			)
			(layer "F.SilkS")
		)
		(fp_line
			(start 0.870458 -0.2794)
			(end 0.845058 0.4064)
			(stroke
				(width 0.1524)
				(type default)
			)
			(layer "F.SilkS")
		)
		(fp_line
			(start 0.94488 -0.450088)
			(end -0.854964 -0.450088)
			(stroke
				(width 0.1524)
				(type default)
			)
			(layer "F.SilkS")
		)
		(fp_line
			(start 0.94488 0.450088)
			(end 0.94488 -0.450088)
			(stroke
				(width 0.1524)
				(type default)
			)
			(layer "F.SilkS")
		)
		(fp_line
			(start -0.54991 -0.350012)
			(end -0.54991 0.350012)
			(stroke
				(width 0.1)
				(type default)
			)
			(layer "F.Fab")
		)
		(fp_line
			(start -0.54991 0.350012)
			(end 0.54991 0.350012)
			(stroke
				(width 0.1)
				(type default)
			)
			(layer "F.Fab")
		)
		(fp_line
			(start 0.54991 -0.350012)
			(end -0.54991 -0.350012)
			(stroke
				(width 0.1)
				(type default)
			)
			(layer "F.Fab")
		)
		(fp_line
			(start 0.54991 0.350012)
			(end 0.54991 -0.350012)
			(stroke
				(width 0.1)
				(type default)
			)
			(layer "F.Fab")
		)
		(fp_text user "+"
			(at -0.635 0.563118 180)
			(unlocked yes)
			(layer "F.SilkS")
			(effects
				(font
					(size 1.905 1.4224)
					(thickness 0.1524)
				)
				(justify left)
			)
		)
		(fp_text user "-"
			(at 2.159 0.563118 180)
			(unlocked yes)
			(layer "F.SilkS")
			(effects
				(font
					(size 1.905 1.4224)
					(thickness 0.1524)
				)
				(justify left)
			)
		)
		(fp_text user "+"
			(at -0.808228 0.239014 180)
			(unlocked yes)
			(layer "F.Fab")
			(effects
				(font
					(size 1.905 1.4224)
					(thickness 0.1524)
				)
				(justify left)
			)
		)
		(fp_text user "-"
			(at 2.48539 0.239014 180)
			(unlocked yes)
			(layer "F.Fab")
			(effects
				(font
					(size 1.905 1.4224)
					(thickness 0.1524)
				)
				(justify left)
			)
		)
		(pad "A" smd rect
			(at -0.424942 0)
			(size 0.5588 0.6096)
			(layers "F.Cu" "F.Mask" "F.Paste")
			(net "GND")
		)
		(pad "C" smd rect
			(at 0.424942 0 180)
			(size 0.5588 0.6096)
			(layers "F.Cu" "F.Mask" "F.Paste")
			(net "FAN_3_OK_R_LED_N")
		)
	)
	(footprint ""
		(layer "F.Cu")
		(at 13.335 -172.466 180)
		(property "Reference" "R5505"
			(at 0 0 180)
			(layer "F.SilkS")
			(hide yes)
			(effects
				(font
					(size 1.27 1.27)
				)
			)
		)
		(property "Value" ""
			(at 0 0 180)
			(layer "F.Fab")
			(effects
				(font
					(size 1.27 1.27)
				)
			)
		)
		(duplicate_pad_numbers_are_jumpers no)
		(fp_line
			(start 0.7874 0.4064)
			(end -0.7874 0.4064)
			(stroke
				(width 0.1524)
				(type default)
			)
			(layer "F.SilkS")
		)
		(fp_line
			(start 0.7874 -0.4064)
			(end 0.7874 0.4064)
			(stroke
				(width 0.1524)
				(type default)
			)
			(layer "F.SilkS")
		)
		(fp_line
			(start -0.7874 0.4064)
			(end -0.7874 -0.4064)
			(stroke
				(width 0.1524)
				(type default)
			)
			(layer "F.SilkS")
		)
		(fp_line
			(start -0.7874 -0.4064)
			(end 0.7874 -0.4064)
			(stroke
				(width 0.1524)
				(type default)
			)
			(layer "F.SilkS")
		)
		(fp_line
			(start 0.67945 0.3048)
			(end 0.120396 0.3048)
			(stroke
				(width 0.1)
				(type default)
			)
			(layer "F.Fab")
		)
		(fp_line
			(start 0.67945 -0.3048)
			(end 0.67945 0.3048)
			(stroke
				(width 0.1)
				(type default)
			)
			(layer "F.Fab")
		)
		(fp_line
			(start 0.12065 -0.2794)
			(end 0.12065 -0.3048)
			(stroke
				(width 0.1)
				(type default)
			)
			(layer "F.Fab")
		)
		(fp_line
			(start 0.12065 -0.3048)
			(end 0.67945 -0.3048)
			(stroke
				(width 0.1)
				(type default)
			)
			(layer "F.Fab")
		)
		(fp_line
			(start 0.120396 0.3048)
			(end 0.120396 0.2794)
			(stroke
				(width 0.1)
				(type default)
			)
			(layer "F.Fab")
		)
		(fp_line
			(start 0.120396 0.2794)
			(end -0.12065 0.2794)
			(stroke
				(width 0.1)
				(type default)
			)
			(layer "F.Fab")
		)
		(fp_line
			(start -0.12065 0.3048)
			(end -0.67945 0.3048)
			(stroke
				(width 0.1)
				(type default)
			)
			(layer "F.Fab")
		)
		(fp_line
			(start -0.12065 0.2794)
			(end -0.12065 0.3048)
			(stroke
				(width 0.1)
				(type default)
			)
			(layer "F.Fab")
		)
		(fp_line
			(start -0.12065 -0.2794)
			(end 0.12065 -0.2794)
			(stroke
				(width 0.1)
				(type default)
			)
			(layer "F.Fab")
		)
		(fp_line
			(start -0.12065 -0.305054)
			(end -0.12065 -0.2794)
			(stroke
				(width 0.1)
				(type default)
			)
			(layer "F.Fab")
		)
		(fp_line
			(start -0.67945 0.3048)
			(end -0.67945 -0.305054)
			(stroke
				(width 0.1)
				(type default)
			)
			(layer "F.Fab")
		)
		(fp_line
			(start -0.67945 -0.305054)
			(end -0.12065 -0.305054)
			(stroke
				(width 0.1)
				(type default)
			)
			(layer "F.Fab")
		)
		(pad "1" smd circle
			(at -0.40005 0 180)
			(size 0 0)
			(layers "F.Cu" "F.Mask" "F.Paste")
			(net "P3V3_AUX")
		)
		(pad "2" smd circle
			(at 0.40005 0 180)
			(size 0 0)
			(layers "F.Cu" "F.Mask" "F.Paste")
			(net "FAN_6_PRESENT_N")
		)
	)
)
